# S9S_MB_2U (Grand Teton) — schematic netlist excerpt (pin names and nets, part order shuffled) for the footprints in the layout excerpt that follows; sources: Cadence DE-HDL packaged netlist, KiCad conversion of 03242023_DA0F0TMBIJ0_F0T_Motherboard_J_brd_V01_OCP.brd

C1926  Q_CAP  0.01UF 50V 10% X7R  pkg C0402  page 217 : A = P3V3_AUX_FPGA_VCCIO0 ; B = GND
C478  Q_CAP  47UF 4V 20% X6S  pkg C0805  page 78 : A = PVCCINFAON_CPU1 ; B = GND
C1313  Q_CAP  10UF 6.3V 20% X6S  pkg C0603  page 210 : A = P3V3_AUX_CLK_GEN_VDDA25M_CK440 ; B = GND

(kicad_pcb
	(version 20260206)
	(generator "pcbnew")
	(generator_version "10.0")
	(general
		(thickness 1.6)
		(legacy_teardrops no)
	)
	(paper "A4")
	(title_block
		(title "03242023_DA0F0TMBIJ0_F0T_Motherboard_J_brd_V01_OCP.brd")
		(comment 1 "Grand Teton / footprints 4940-4942 of 6105")
	)
	(layers
		(0 "F.Cu" signal "TOP")
		(4 "In1.Cu" signal "GND")
		(6 "In2.Cu" signal "IN1")
		(8 "In3.Cu" signal "GND1")
		(10 "In4.Cu" signal "IN2")
		(12 "In5.Cu" signal "GND2")
		(14 "In6.Cu" signal "IN3")
		(16 "In7.Cu" signal "GND3")
		(18 "In8.Cu" signal "VCC")
		(20 "In9.Cu" signal "VCC1")
		(22 "In10.Cu" signal "GND4")
		(24 "In11.Cu" signal "IN4")
		(26 "In12.Cu" signal "GND5")
		(28 "In13.Cu" signal "IN5")
		(30 "In14.Cu" signal "GND6")
		(32 "In15.Cu" signal "IN6")
		(34 "In16.Cu" signal "GND7")
		(2 "B.Cu" signal "BOTTOM")
		(9 "F.Adhes" user "F.Adhesive")
		(11 "B.Adhes" user "B.Adhesive")
		(13 "F.Paste" user "Package Geometry/Pastemask Top")
		(15 "B.Paste" user "Package Geometry/Pastemask Bottom")
		(5 "F.SilkS" user "Ref Des/Silkscreen Top")
		(7 "B.SilkS" user "Ref Des/Silkscreen Bottom")
		(1 "F.Mask" user "Board Geometry/Soldermask Top")
		(3 "B.Mask" user "Board Geometry/Soldermask Bottom")
		(17 "Dwgs.User" user "User.Drawings")
		(19 "Cmts.User" user "User.Comments")
		(21 "Eco1.User" user "User.Eco1")
		(23 "Eco2.User" user "User.Eco2")
		(25 "Edge.Cuts" user "Board Geometry/Outline")
		(27 "Margin" user)
		(31 "F.CrtYd" user "Package Geometry/Place Bound Top")
		(29 "B.CrtYd" user "Package Geometry/Place Bound Bottom")
		(35 "F.Fab" user "Ref Des/Assembly Top")
		(33 "B.Fab" user "Ref Des/Assembly Bottom")
	)
	(footprint ""
		(layer "B.Cu")
		(at 252.349 -100.613718 180)
		(property "Reference" "C1313"
			(at 0 0 0)
			(layer "B.SilkS")
			(hide yes)
			(effects
				(font
					(size 1.27 1.27)
				)
				(justify mirror)
			)
		)
		(property "Value" ""
			(at 0 0 0)
			(layer "B.Fab")
			(effects
				(font
					(size 1.27 1.27)
				)
				(justify mirror)
			)
		)
		(duplicate_pad_numbers_are_jumpers no)
		(fp_line
			(start 1.2954 0.5842)
			(end 1.2954 -0.5842)
			(stroke
				(width 0.1524)
				(type default)
			)
			(layer "B.SilkS")
		)
		(fp_line
			(start 1.2954 -0.5842)
			(end -1.2954 -0.5842)
			(stroke
				(width 0.1524)
				(type default)
			)
			(layer "B.SilkS")
		)
		(fp_line
			(start 0 -0.5842)
			(end 0 0.5842)
			(stroke
				(width 0.1524)
				(type default)
			)
			(layer "B.SilkS")
		)
		(fp_line
			(start -1.2954 0.5842)
			(end 1.2954 0.5842)
			(stroke
				(width 0.1524)
				(type default)
			)
			(layer "B.SilkS")
		)
		(fp_line
			(start -1.2954 -0.5842)
			(end -1.2954 0.5842)
			(stroke
				(width 0.1524)
				(type default)
			)
			(layer "B.SilkS")
		)
		(fp_line
			(start 1.1938 0.4064)
			(end 1.1938 -0.4064)
			(stroke
				(width 0.1)
				(type default)
			)
			(layer "B.Fab")
		)
		(fp_line
			(start 1.1938 -0.4064)
			(end 0.8636 -0.4064)
			(stroke
				(width 0.1)
				(type default)
			)
			(layer "B.Fab")
		)
		(fp_line
			(start 0.8636 0.4572)
			(end 0.8636 0.4064)
			(stroke
				(width 0.1)
				(type default)
			)
			(layer "B.Fab")
		)
		(fp_line
			(start 0.8636 0.4064)
			(end 1.1938 0.4064)
			(stroke
				(width 0.1)
				(type default)
			)
			(layer "B.Fab")
		)
		(fp_line
			(start 0.8636 -0.4064)
			(end 0.8636 -0.4572)
			(stroke
				(width 0.1)
				(type default)
			)
			(layer "B.Fab")
		)
		(fp_line
			(start 0.8636 -0.4572)
			(end -0.8636 -0.4572)
			(stroke
				(width 0.1)
				(type default)
			)
			(layer "B.Fab")
		)
		(fp_line
			(start -0.8636 0.4572)
			(end 0.8636 0.4572)
			(stroke
				(width 0.1)
				(type default)
			)
			(layer "B.Fab")
		)
		(fp_line
			(start -0.8636 0.4064)
			(end -0.8636 0.4572)
			(stroke
				(width 0.1)
				(type default)
			)
			(layer "B.Fab")
		)
		(fp_line
			(start -0.8636 -0.4064)
			(end -1.1938 -0.4064)
			(stroke
				(width 0.1)
				(type default)
			)
			(layer "B.Fab")
		)
		(fp_line
			(start -0.8636 -0.4572)
			(end -0.8636 -0.4064)
			(stroke
				(width 0.1)
				(type default)
			)
			(layer "B.Fab")
		)
		(fp_line
			(start -1.1938 0.4064)
			(end -0.8636 0.4064)
			(stroke
				(width 0.1)
				(type default)
			)
			(layer "B.Fab")
		)
		(fp_line
			(start -1.1938 -0.4064)
			(end -1.1938 0.4064)
			(stroke
				(width 0.1)
				(type default)
			)
			(layer "B.Fab")
		)
		(pad "1" smd rect
			(at 0.7366 0 90)
			(size 0.7112 0.8128)
			(layers "B.Cu" "B.Mask" "B.Paste")
			(net "P3V3_AUX_CLK_GEN_VDDA25M_CK440")
		)
		(pad "2" smd rect
			(at -0.7366 0 90)
			(size 0.7112 0.8128)
			(layers "B.Cu" "B.Mask" "B.Paste")
			(net "GND")
		)
	)
	(footprint ""
		(layer "B.Cu")
		(at 119.95912 -259.53212 90)
		(property "Reference" "C478"
			(at 0 0 90)
			(layer "B.SilkS")
			(hide yes)
			(effects
				(font
					(size 1.27 1.27)
				)
				(justify mirror)
			)
		)
		(property "Value" ""
			(at 0 0 90)
			(layer "B.Fab")
			(effects
				(font
					(size 1.27 1.27)
				)
				(justify mirror)
			)
		)
		(duplicate_pad_numbers_are_jumpers no)
		(fp_line
			(start 1.524 -0.762)
			(end -1.524 -0.762)
			(stroke
				(width 0.1524)
				(type default)
			)
			(layer "B.SilkS")
		)
		(fp_line
			(start -1.524 -0.762)
			(end -1.524 0.762)
			(stroke
				(width 0.1524)
				(type default)
			)
			(layer "B.SilkS")
		)
		(fp_line
			(start 1.524 0.762)
			(end 1.524 -0.762)
			(stroke
				(width 0.1524)
				(type default)
			)
			(layer "B.SilkS")
		)
		(fp_line
			(start -1.524 0.762)
			(end 1.524 0.762)
			(stroke
				(width 0.1524)
				(type default)
			)
			(layer "B.SilkS")
		)
		(fp_line
			(start 1.1049 -0.724916)
			(end 1.1049 0.724916)
			(stroke
				(width 0.1)
				(type default)
			)
			(layer "B.Fab")
		)
		(fp_line
			(start -1.1049 -0.724916)
			(end 1.1049 -0.724916)
			(stroke
				(width 0.1)
				(type default)
			)
			(layer "B.Fab")
		)
		(fp_line
			(start 1.1049 0.724916)
			(end -1.1049 0.724916)
			(stroke
				(width 0.1)
				(type default)
			)
			(layer "B.Fab")
		)
		(fp_line
			(start -1.1049 0.724916)
			(end -1.1049 -0.724916)
			(stroke
				(width 0.1)
				(type default)
			)
			(layer "B.Fab")
		)
		(pad "1" smd rect
			(at 0.889 0 90)
			(size 1.016 1.27)
			(layers "B.Cu" "B.Mask" "B.Paste")
			(net "PVCCINFAON_CPU1")
		)
		(pad "2" smd rect
			(at -0.889 0 90)
			(size 1.016 1.27)
			(layers "B.Cu" "B.Mask" "B.Paste")
			(net "GND")
		)
	)
	(footprint ""
		(layer "B.Cu")
		(at 175.355758 -115.375436 180)
		(property "Reference" "C1926"
			(at 0 0 0)
			(layer "B.SilkS")
			(hide yes)
			(effects
				(font
					(size 1.27 1.27)
				)
				(justify mirror)
			)
		)
		(property "Value" ""
			(at 0 0 0)
			(layer "B.Fab")
			(effects
				(font
					(size 1.27 1.27)
				)
				(justify mirror)
			)
		)
		(duplicate_pad_numbers_are_jumpers no)
		(fp_line
			(start 0.69215 0.2921)
			(end 0.69215 -0.2921)
			(stroke
				(width 0.1524)
				(type default)
			)
			(layer "B.SilkS")
		)
		(fp_line
			(start 0.69215 -0.2921)
			(end -0.69215 -0.2921)
			(stroke
				(width 0.1524)
				(type default)
			)
			(layer "B.SilkS")
		)
		(fp_line
			(start -0.69215 0.2921)
			(end 0.69215 0.2921)
			(stroke
				(width 0.1524)
				(type default)
			)
			(layer "B.SilkS")
		)
		(fp_line
			(start -0.69215 -0.2921)
			(end -0.69215 0.2921)
			(stroke
				(width 0.1524)
				(type default)
			)
			(layer "B.SilkS")
		)
		(fp_line
			(start 0.51435 0.2794)
			(end 0.51435 -0.2794)
			(stroke
				(width 0.1)
				(type default)
			)
			(layer "B.Fab")
		)
		(fp_line
			(start 0.51435 -0.2794)
			(end -0.51435 -0.2794)
			(stroke
				(width 0.1)
				(type default)
			)
			(layer "B.Fab")
		)
		(fp_line
			(start -0.51435 0.2794)
			(end 0.51435 0.2794)
			(stroke
				(width 0.1)
				(type default)
			)
			(layer "B.Fab")
		)
		(fp_line
			(start -0.51435 -0.2794)
			(end -0.51435 0.2794)
			(stroke
				(width 0.1)
				(type default)
			)
			(layer "B.Fab")
		)
		(pad "1" smd circle
			(at 0.40005 0)
			(size 0 0)
			(layers "B.Cu" "B.Mask" "B.Paste")
			(net "P3V3_AUX_FPGA_VCCIO0")
		)
		(pad "2" smd circle
			(at -0.40005 0)
			(size 0 0)
			(layers "B.Cu" "B.Mask" "B.Paste")
			(net "GND")
		)
		(zone
			(layer "B.Cu")
			(hatch none 0.5)
			(connect_pads
				(clearance 0)
			)
			(min_thickness 0.25)
			(keepout
				(tracks not_allowed)
				(vias allowed)
				(pads allowed)
				(copperpour not_allowed)
				(footprints allowed)
			)
			(placement
				(enabled no)
				(sheetname "")
			)
			(fill
				(thermal_gap 0.5)
				(thermal_bridge_width 0.5)
				(island_removal_mode 0)
			)
			(polygon
				(pts
					(xy 175.165258 -115.463066) (xy 175.256698 -115.521232) (xy 175.456088 -115.521232) (xy 175.546258 -115.463066)
					(xy 175.546258 -115.287806) (xy 175.456088 -115.229386) (xy 175.256698 -115.229386) (xy 175.165258 -115.287552)
				)
			)
		)
	)
)
